(kicad_pcb
	(version 20260206)
	(generator "pcbnew")
	(generator_version "10.0")
	(general
		(thickness 1.6)
		(legacy_teardrops no)
	)
	(paper "A4")
	(title_block
		(title "04192023_DAF0TMB3IC0_F0TG_MB_C_brd_V02_OCP.brd")
		(comment 1 "Grand Teton / footprints 5607-5613 of 8354")
	)
	(layers
		(0 "F.Cu" signal "TOP")
		(4 "In1.Cu" signal "GND")
		(6 "In2.Cu" signal "IN1")
		(8 "In3.Cu" signal "GND1")
		(10 "In4.Cu" signal "IN2")
		(12 "In5.Cu" signal "GND2")
		(14 "In6.Cu" signal "IN3")
		(16 "In7.Cu" signal "GND3")
		(18 "In8.Cu" signal "VCC")
		(20 "In9.Cu" signal "VCC1")
		(22 "In10.Cu" signal "GND4")
		(24 "In11.Cu" signal "IN4")
		(26 "In12.Cu" signal "GND5")
		(28 "In13.Cu" signal "IN5")
		(30 "In14.Cu" signal "GND6")
		(32 "In15.Cu" signal "IN6")
		(34 "In16.Cu" signal "GND7")
		(2 "B.Cu" signal "BOTTOM")
		(9 "F.Adhes" user "F.Adhesive")
		(11 "B.Adhes" user "B.Adhesive")
		(13 "F.Paste" user "Package Geometry/Pastemask Top")
		(15 "B.Paste" user "Package Geometry/Pastemask Bottom")
		(5 "F.SilkS" user "Ref Des/Silkscreen Top")
		(7 "B.SilkS" user "Ref Des/Silkscreen Bottom")
		(1 "F.Mask" user "Board Geometry/Soldermask Top")
		(3 "B.Mask" user "Board Geometry/Soldermask Bottom")
		(17 "Dwgs.User" user "User.Drawings")
		(19 "Cmts.User" user "User.Comments")
		(21 "Eco1.User" user "User.Eco1")
		(23 "Eco2.User" user "User.Eco2")
		(25 "Edge.Cuts" user "Board Geometry/Outline")
		(27 "Margin" user)
		(31 "F.CrtYd" user "Package Geometry/Place Bound Top")
		(29 "B.CrtYd" user "Package Geometry/Place Bound Bottom")
		(35 "F.Fab" user "Ref Des/Assembly Top")
		(33 "B.Fab" user "Ref Des/Assembly Bottom")
	)
	(footprint ""
		(layer "B.Cu")
		(at 347.008958 -249.36831 180)
		(property "Reference" "C2513"
			(at 0 0 0)
			(layer "B.SilkS")
			(hide yes)
			(effects
				(font
					(size 1.27 1.27)
				)
				(justify mirror)
			)
		)
		(property "Value" ""
			(at 0 0 0)
			(layer "B.Fab")
			(effects
				(font
					(size 1.27 1.27)
				)
				(justify mirror)
			)
		)
		(duplicate_pad_numbers_are_jumpers no)
		(fp_line
			(start 0.7874 0.4064)
			(end 0.7874 -0.4064)
			(stroke
				(width 0.1524)
				(type default)
			)
			(layer "B.SilkS")
		)
		(fp_line
			(start 0.7874 -0.4064)
			(end -0.7874 -0.4064)
			(stroke
				(width 0.1524)
				(type default)
			)
			(layer "B.SilkS")
		)
		(fp_line
			(start -0.7874 0.4064)
			(end 0.7874 0.4064)
			(stroke
				(width 0.1524)
				(type default)
			)
			(layer "B.SilkS")
		)
		(fp_line
			(start -0.7874 -0.4064)
			(end -0.7874 0.4064)
			(stroke
				(width 0.1524)
				(type default)
			)
			(layer "B.SilkS")
		)
		(fp_line
			(start 0.67945 0.3048)
			(end 0.67945 -0.305054)
			(stroke
				(width 0.1)
				(type default)
			)
			(layer "B.Fab")
		)
		(fp_line
			(start 0.67945 -0.305054)
			(end 0.12065 -0.305054)
			(stroke
				(width 0.1)
				(type default)
			)
			(layer "B.Fab")
		)
		(fp_line
			(start 0.12065 0.3048)
			(end 0.67945 0.3048)
			(stroke
				(width 0.1)
				(type default)
			)
			(layer "B.Fab")
		)
		(fp_line
			(start 0.12065 0.2794)
			(end 0.12065 0.3048)
			(stroke
				(width 0.1)
				(type default)
			)
			(layer "B.Fab")
		)
		(fp_line
			(start 0.12065 -0.2794)
			(end -0.12065 -0.2794)
			(stroke
				(width 0.1)
				(type default)
			)
			(layer "B.Fab")
		)
		(fp_line
			(start 0.12065 -0.305054)
			(end 0.12065 -0.2794)
			(stroke
				(width 0.1)
				(type default)
			)
			(layer "B.Fab")
		)
		(fp_line
			(start -0.120396 0.3048)
			(end -0.120396 0.2794)
			(stroke
				(width 0.1)
				(type default)
			)
			(layer "B.Fab")
		)
		(fp_line
			(start -0.120396 0.2794)
			(end 0.12065 0.2794)
			(stroke
				(width 0.1)
				(type default)
			)
			(layer "B.Fab")
		)
		(fp_line
			(start -0.12065 -0.2794)
			(end -0.12065 -0.3048)
			(stroke
				(width 0.1)
				(type default)
			)
			(layer "B.Fab")
		)
		(fp_line
			(start -0.12065 -0.3048)
			(end -0.67945 -0.3048)
			(stroke
				(width 0.1)
				(type default)
			)
			(layer "B.Fab")
		)
		(fp_line
			(start -0.67945 0.3048)
			(end -0.120396 0.3048)
			(stroke
				(width 0.1)
				(type default)
			)
			(layer "B.Fab")
		)
		(fp_line
			(start -0.67945 -0.3048)
			(end -0.67945 0.3048)
			(stroke
				(width 0.1)
				(type default)
			)
			(layer "B.Fab")
		)
		(pad "1" smd circle
			(at 0.40005 0)
			(size 0 0)
			(layers "B.Cu" "B.Mask" "B.Paste")
			(net "PVDD18_S5_P0")
		)
		(pad "2" smd circle
			(at -0.40005 0)
			(size 0 0)
			(layers "B.Cu" "B.Mask" "B.Paste")
			(net "GND")
		)
	)
	(footprint ""
		(layer "B.Cu")
		(at 298.901104 -427.261528 180)
		(property "Reference" "C1073"
			(at 0 0 0)
			(layer "B.SilkS")
			(hide yes)
			(effects
				(font
					(size 1.27 1.27)
				)
				(justify mirror)
			)
		)
		(property "Value" ""
			(at 0 0 0)
			(layer "B.Fab")
			(effects
				(font
					(size 1.27 1.27)
				)
				(justify mirror)
			)
		)
		(duplicate_pad_numbers_are_jumpers no)
		(fp_line
			(start 0.299974 0.150114)
			(end 0.299974 -0.150114)
			(stroke
				(width 0.1)
				(type default)
			)
			(layer "B.Fab")
		)
		(fp_line
			(start 0.299974 -0.150114)
			(end -0.299974 -0.150114)
			(stroke
				(width 0.1)
				(type default)
			)
			(layer "B.Fab")
		)
		(fp_line
			(start -0.299974 0.150114)
			(end 0.299974 0.150114)
			(stroke
				(width 0.1)
				(type default)
			)
			(layer "B.Fab")
		)
		(fp_line
			(start -0.299974 -0.150114)
			(end -0.299974 0.150114)
			(stroke
				(width 0.1)
				(type default)
			)
			(layer "B.Fab")
		)
		(pad "1" smd rect
			(at 0.2667 0)
			(size 0.3048 0.381)
			(layers "B.Cu" "B.Mask" "B.Paste")
			(net "P3V3_AUX")
		)
		(pad "2" smd rect
			(at -0.2667 0)
			(size 0.3048 0.381)
			(layers "B.Cu" "B.Mask" "B.Paste")
			(net "GND")
		)
	)
	(footprint ""
		(layer "B.Cu")
		(at 445.888618 -193.99631)
		(property "Reference" "C132"
			(at 0 0 0)
			(layer "B.SilkS")
			(hide yes)
			(effects
				(font
					(size 1.27 1.27)
				)
				(justify mirror)
			)
		)
		(property "Value" ""
			(at 0 0 0)
			(layer "B.Fab")
			(effects
				(font
					(size 1.27 1.27)
				)
				(justify mirror)
			)
		)
		(duplicate_pad_numbers_are_jumpers no)
		(fp_line
			(start -0.7874 -0.4064)
			(end -0.7874 0.4064)
			(stroke
				(width 0.1524)
				(type default)
			)
			(layer "B.SilkS")
		)
		(fp_line
			(start -0.7874 0.4064)
			(end 0.7874 0.4064)
			(stroke
				(width 0.1524)
				(type default)
			)
			(layer "B.SilkS")
		)
		(fp_line
			(start 0.7874 -0.4064)
			(end -0.7874 -0.4064)
			(stroke
				(width 0.1524)
				(type default)
			)
			(layer "B.SilkS")
		)
		(fp_line
			(start 0.7874 0.4064)
			(end 0.7874 -0.4064)
			(stroke
				(width 0.1524)
				(type default)
			)
			(layer "B.SilkS")
		)
		(fp_line
			(start -0.67945 -0.3048)
			(end -0.67945 0.3048)
			(stroke
				(width 0.1)
				(type default)
			)
			(layer "B.Fab")
		)
		(fp_line
			(start -0.67945 0.3048)
			(end -0.120396 0.3048)
			(stroke
				(width 0.1)
				(type default)
			)
			(layer "B.Fab")
		)
		(fp_line
			(start -0.12065 -0.3048)
			(end -0.67945 -0.3048)
			(stroke
				(width 0.1)
				(type default)
			)
			(layer "B.Fab")
		)
		(fp_line
			(start -0.12065 -0.2794)
			(end -0.12065 -0.3048)
			(stroke
				(width 0.1)
				(type default)
			)
			(layer "B.Fab")
		)
		(fp_line
			(start -0.120396 0.2794)
			(end 0.12065 0.2794)
			(stroke
				(width 0.1)
				(type default)
			)
			(layer "B.Fab")
		)
		(fp_line
			(start -0.120396 0.3048)
			(end -0.120396 0.2794)
			(stroke
				(width 0.1)
				(type default)
			)
			(layer "B.Fab")
		)
		(fp_line
			(start 0.12065 -0.305054)
			(end 0.12065 -0.2794)
			(stroke
				(width 0.1)
				(type default)
			)
			(layer "B.Fab")
		)
		(fp_line
			(start 0.12065 -0.2794)
			(end -0.12065 -0.2794)
			(stroke
				(width 0.1)
				(type default)
			)
			(layer "B.Fab")
		)
		(fp_line
			(start 0.12065 0.2794)
			(end 0.12065 0.3048)
			(stroke
				(width 0.1)
				(type default)
			)
			(layer "B.Fab")
		)
		(fp_line
			(start 0.12065 0.3048)
			(end 0.67945 0.3048)
			(stroke
				(width 0.1)
				(type default)
			)
			(layer "B.Fab")
		)
		(fp_line
			(start 0.67945 -0.305054)
			(end 0.12065 -0.305054)
			(stroke
				(width 0.1)
				(type default)
			)
			(layer "B.Fab")
		)
		(fp_line
			(start 0.67945 0.3048)
			(end 0.67945 -0.305054)
			(stroke
				(width 0.1)
				(type default)
			)
			(layer "B.Fab")
		)
		(pad "1" smd circle
			(at 0.40005 0 180)
			(size 0 0)
			(layers "B.Cu" "B.Mask" "B.Paste")
			(net "P3V3_AUX")
		)
		(pad "2" smd circle
			(at -0.40005 0 180)
			(size 0 0)
			(layers "B.Cu" "B.Mask" "B.Paste")
			(net "GND")
		)
	)
	(footprint ""
		(layer "B.Cu")
		(at 62.467744 -408.517344 90)
		(property "Reference" "C6669"
			(at 0 0 90)
			(layer "B.SilkS")
			(hide yes)
			(effects
				(font
					(size 1.27 1.27)
				)
				(justify mirror)
			)
		)
		(property "Value" ""
			(at 0 0 90)
			(layer "B.Fab")
			(effects
				(font
					(size 1.27 1.27)
				)
				(justify mirror)
			)
		)
		(duplicate_pad_numbers_are_jumpers no)
		(fp_line
			(start 0.299974 -0.150114)
			(end -0.299974 -0.150114)
			(stroke
				(width 0.1)
				(type default)
			)
			(layer "B.Fab")
		)
		(fp_line
			(start -0.299974 -0.150114)
			(end -0.299974 0.150114)
			(stroke
				(width 0.1)
				(type default)
			)
			(layer "B.Fab")
		)
		(fp_line
			(start 0.299974 0.150114)
			(end 0.299974 -0.150114)
			(stroke
				(width 0.1)
				(type default)
			)
			(layer "B.Fab")
		)
		(fp_line
			(start -0.299974 0.150114)
			(end 0.299974 0.150114)
			(stroke
				(width 0.1)
				(type default)
			)
			(layer "B.Fab")
		)
		(pad "1" smd rect
			(at 0.2667 0 270)
			(size 0.3048 0.381)
			(layers "B.Cu" "B.Mask" "B.Paste")
			(net "P5E_CPU1_P1_TX_BUF_C_DP<4>")
		)
		(pad "2" smd rect
			(at -0.2667 0 270)
			(size 0.3048 0.381)
			(layers "B.Cu" "B.Mask" "B.Paste")
			(net "P5E_CPU1_P1_TX_BUF_DP<4>")
		)
	)
	(footprint ""
		(layer "B.Cu")
		(at 172.456094 -413.776668)
		(property "Reference" "R2915"
			(at 0 0 0)
			(layer "B.SilkS")
			(hide yes)
			(effects
				(font
					(size 1.27 1.27)
				)
				(justify mirror)
			)
		)
		(property "Value" ""
			(at 0 0 0)
			(layer "B.Fab")
			(effects
				(font
					(size 1.27 1.27)
				)
				(justify mirror)
			)
		)
		(duplicate_pad_numbers_are_jumpers no)
		(fp_line
			(start -0.7874 -0.4064)
			(end -0.7874 0.4064)
			(stroke
				(width 0.1524)
				(type default)
			)
			(layer "B.SilkS")
		)
		(fp_line
			(start -0.7874 0.4064)
			(end 0.7874 0.4064)
			(stroke
				(width 0.1524)
				(type default)
			)
			(layer "B.SilkS")
		)
		(fp_line
			(start 0.7874 -0.4064)
			(end -0.7874 -0.4064)
			(stroke
				(width 0.1524)
				(type default)
			)
			(layer "B.SilkS")
		)
		(fp_line
			(start 0.7874 0.4064)
			(end 0.7874 -0.4064)
			(stroke
				(width 0.1524)
				(type default)
			)
			(layer "B.SilkS")
		)
		(fp_line
			(start -0.67945 -0.3048)
			(end -0.67945 0.3048)
			(stroke
				(width 0.1)
				(type default)
			)
			(layer "B.Fab")
		)
		(fp_line
			(start -0.67945 0.3048)
			(end -0.120396 0.3048)
			(stroke
				(width 0.1)
				(type default)
			)
			(layer "B.Fab")
		)
		(fp_line
			(start -0.12065 -0.3048)
			(end -0.67945 -0.3048)
			(stroke
				(width 0.1)
				(type default)
			)
			(layer "B.Fab")
		)
		(fp_line
			(start -0.12065 -0.2794)
			(end -0.12065 -0.3048)
			(stroke
				(width 0.1)
				(type default)
			)
			(layer "B.Fab")
		)
		(fp_line
			(start -0.120396 0.2794)
			(end 0.12065 0.2794)
			(stroke
				(width 0.1)
				(type default)
			)
			(layer "B.Fab")
		)
		(fp_line
			(start -0.120396 0.3048)
			(end -0.120396 0.2794)
			(stroke
				(width 0.1)
				(type default)
			)
			(layer "B.Fab")
		)
		(fp_line
			(start 0.12065 -0.305054)
			(end 0.12065 -0.2794)
			(stroke
				(width 0.1)
				(type default)
			)
			(layer "B.Fab")
		)
		(fp_line
			(start 0.12065 -0.2794)
			(end -0.12065 -0.2794)
			(stroke
				(width 0.1)
				(type default)
			)
			(layer "B.Fab")
		)
		(fp_line
			(start 0.12065 0.2794)
			(end 0.12065 0.3048)
			(stroke
				(width 0.1)
				(type default)
			)
			(layer "B.Fab")
		)
		(fp_line
			(start 0.12065 0.3048)
			(end 0.67945 0.3048)
			(stroke
				(width 0.1)
				(type default)
			)
			(layer "B.Fab")
		)
		(fp_line
			(start 0.67945 -0.305054)
			(end 0.12065 -0.305054)
			(stroke
				(width 0.1)
				(type default)
			)
			(layer "B.Fab")
		)
		(fp_line
			(start 0.67945 0.3048)
			(end 0.67945 -0.305054)
			(stroke
				(width 0.1)
				(type default)
			)
			(layer "B.Fab")
		)
		(pad "1" smd circle
			(at 0.40005 0 180)
			(size 0 0)
			(layers "B.Cu" "B.Mask" "B.Paste")
			(net "BMC_MONITER_R")
		)
		(pad "2" smd circle
			(at -0.40005 0 180)
			(size 0 0)
			(layers "B.Cu" "B.Mask" "B.Paste")
			(net "GND")
		)
	)
	(footprint ""
		(layer "B.Cu")
		(at 423.63009 -359.84434)
		(property "Reference" "R8116"
			(at 0 0 0)
			(layer "B.SilkS")
			(hide yes)
			(effects
				(font
					(size 1.27 1.27)
				)
				(justify mirror)
			)
		)
		(property "Value" ""
			(at 0 0 0)
			(layer "B.Fab")
			(effects
				(font
					(size 1.27 1.27)
				)
				(justify mirror)
			)
		)
		(duplicate_pad_numbers_are_jumpers no)
		(fp_line
			(start -0.7874 -0.4064)
			(end -0.7874 0.4064)
			(stroke
				(width 0.1524)
				(type default)
			)
			(layer "B.SilkS")
		)
		(fp_line
			(start -0.7874 0.4064)
			(end 0.7874 0.4064)
			(stroke
				(width 0.1524)
				(type default)
			)
			(layer "B.SilkS")
		)
		(fp_line
			(start 0.7874 -0.4064)
			(end -0.7874 -0.4064)
			(stroke
				(width 0.1524)
				(type default)
			)
			(layer "B.SilkS")
		)
		(fp_line
			(start 0.7874 0.4064)
			(end 0.7874 -0.4064)
			(stroke
				(width 0.1524)
				(type default)
			)
			(layer "B.SilkS")
		)
		(fp_line
			(start -0.67945 -0.3048)
			(end -0.67945 0.3048)
			(stroke
				(width 0.1)
				(type default)
			)
			(layer "B.Fab")
		)
		(fp_line
			(start -0.67945 0.3048)
			(end -0.120396 0.3048)
			(stroke
				(width 0.1)
				(type default)
			)
			(layer "B.Fab")
		)
		(fp_line
			(start -0.12065 -0.3048)
			(end -0.67945 -0.3048)
			(stroke
				(width 0.1)
				(type default)
			)
			(layer "B.Fab")
		)
		(fp_line
			(start -0.12065 -0.2794)
			(end -0.12065 -0.3048)
			(stroke
				(width 0.1)
				(type default)
			)
			(layer "B.Fab")
		)
		(fp_line
			(start -0.120396 0.2794)
			(end 0.12065 0.2794)
			(stroke
				(width 0.1)
				(type default)
			)
			(layer "B.Fab")
		)
		(fp_line
			(start -0.120396 0.3048)
			(end -0.120396 0.2794)
			(stroke
				(width 0.1)
				(type default)
			)
			(layer "B.Fab")
		)
		(fp_line
			(start 0.12065 -0.305054)
			(end 0.12065 -0.2794)
			(stroke
				(width 0.1)
				(type default)
			)
			(layer "B.Fab")
		)
		(fp_line
			(start 0.12065 -0.2794)
			(end -0.12065 -0.2794)
			(stroke
				(width 0.1)
				(type default)
			)
			(layer "B.Fab")
		)
		(fp_line
			(start 0.12065 0.2794)
			(end 0.12065 0.3048)
			(stroke
				(width 0.1)
				(type default)
			)
			(layer "B.Fab")
		)
		(fp_line
			(start 0.12065 0.3048)
			(end 0.67945 0.3048)
			(stroke
				(width 0.1)
				(type default)
			)
			(layer "B.Fab")
		)
		(fp_line
			(start 0.67945 -0.305054)
			(end 0.12065 -0.305054)
			(stroke
				(width 0.1)
				(type default)
			)
			(layer "B.Fab")
		)
		(fp_line
			(start 0.67945 0.3048)
			(end 0.67945 -0.305054)
			(stroke
				(width 0.1)
				(type default)
			)
			(layer "B.Fab")
		)
		(pad "1" smd circle
			(at 0.40005 0 180)
			(size 0 0)
			(layers "B.Cu" "B.Mask" "B.Paste")
			(net "PVDD11_S3_P0_OCP_N")
		)
		(pad "2" smd circle
			(at -0.40005 0 180)
			(size 0 0)
			(layers "B.Cu" "B.Mask" "B.Paste")
			(net "PVDD11_S3_P0_OCP_N_R")
		)
	)
	(footprint ""
		(layer "B.Cu")
		(at 232.857802 -248.53265)
		(property "Reference" "U4"
			(at 1.58496 -2.89687 0)
			(unlocked yes)
			(layer "B.SilkS")
			(effects
				(font
					(size 0.7874 0.5842)
					(thickness 0.1524)
				)
				(justify mirror)
			)
		)
		(property "Value" ""
			(at 0 0 0)
			(layer "B.Fab")
			(effects
				(font
					(size 1.27 1.27)
				)
				(justify mirror)
			)
		)
		(duplicate_pad_numbers_are_jumpers no)
		(fp_line
			(start -1.03378 -1.284478)
			(end -1.03378 1.284478)
			(stroke
				(width 0.1524)
				(type default)
			)
			(layer "B.SilkS")
		)
		(fp_line
			(start -1.03378 1.284478)
			(end 1.03378 1.284478)
			(stroke
				(width 0.1524)
				(type default)
			)
			(layer "B.SilkS")
		)
		(fp_line
			(start 1.03378 -1.284478)
			(end -1.03378 -1.284478)
			(stroke
				(width 0.1524)
				(type default)
			)
			(layer "B.SilkS")
		)
		(fp_line
			(start 1.03378 1.284478)
			(end 1.03378 -1.284478)
			(stroke
				(width 0.1524)
				(type default)
			)
			(layer "B.SilkS")
		)
		(fp_poly
			(pts
				(xy 1.806702 -1.052576) (xy 1.806702 -0.447548) (xy 1.201674 -0.750062)
			)
			(stroke
				(width 0)
				(type default)
			)
			(fill yes)
			(layer "B.SilkS")
		)
		(fp_line
			(start -0.774954 -1.02489)
			(end -0.774954 1.02489)
			(stroke
				(width 0.1)
				(type default)
			)
			(layer "B.Fab")
		)
		(fp_line
			(start -0.774954 1.02489)
			(end 0.774954 1.02489)
			(stroke
				(width 0.1)
				(type default)
			)
			(layer "B.Fab")
		)
		(fp_line
			(start 0.774954 -1.02489)
			(end -0.774954 -1.02489)
			(stroke
				(width 0.1)
				(type default)
			)
			(layer "B.Fab")
		)
		(fp_line
			(start 0.774954 1.02489)
			(end 0.774954 -1.02489)
			(stroke
				(width 0.1)
				(type default)
			)
			(layer "B.Fab")
		)
		(fp_poly
			(pts
				(xy 1.201674 -0.750062) (xy 1.806702 -0.447548) (xy 1.806702 -1.052576)
			)
			(stroke
				(width 0)
				(type default)
			)
			(fill yes)
			(layer "B.Fab")
		)
		(pad "1" smd rect
			(at 0.64008 -0.750062 90)
			(size 0.3048 0.5334)
			(layers "B.Cu" "B.Mask" "B.Paste")
			(net "SMB_APML_CPU0_MUX2_SCL")
		)
		(pad "2" smd rect
			(at 0.64008 -0.249936 90)
			(size 0.254 0.5334)
			(layers "B.Cu" "B.Mask" "B.Paste")
			(net "SMB_APML_CPU0_MUX2_SDA")
		)
		(pad "3" smd rect
			(at 0.64008 0.249936 90)
			(size 0.254 0.5334)
			(layers "B.Cu" "B.Mask" "B.Paste")
			(net "SMB_APML_CPU1_MUX2_SCL")
		)
		(pad "4" smd rect
			(at 0.64008 0.750062 90)
			(size 0.3048 0.5334)
			(layers "B.Cu" "B.Mask" "B.Paste")
			(net "SMB_APML_CPU1_MUX2_SDA")
		)
		(pad "5" smd rect
			(at 0 0.839978 180)
			(size 0.3302 0.635)
			(layers "B.Cu" "B.Mask" "B.Paste")
			(net "GND")
		)
		(pad "6" smd rect
			(at -0.64008 0.750062 90)
			(size 0.3048 0.5334)
			(layers "B.Cu" "B.Mask" "B.Paste")
			(net "FM_APML_MUX2_OE_N")
		)
		(pad "7" smd rect
			(at -0.64008 0.249936 90)
			(size 0.254 0.5334)
			(layers "B.Cu" "B.Mask" "B.Paste")
			(net "SMB_CPU0_CPU1_APML_MUX2_SDA")
		)
		(pad "8" smd rect
			(at -0.64008 -0.249936 90)
			(size 0.254 0.5334)
			(layers "B.Cu" "B.Mask" "B.Paste")
			(net "SMB_CPU0_CPU1_APML_MUX2_SCL")
		)
		(pad "9" smd rect
			(at -0.64008 -0.750062 90)
			(size 0.3048 0.5334)
			(layers "B.Cu" "B.Mask" "B.Paste")
			(net "FM_APML_MUX2_SEL")
		)
		(pad "10" smd rect
			(at 0 -0.839978 180)
			(size 0.3302 0.635)
			(layers "B.Cu" "B.Mask" "B.Paste")
			(net "P3V3_AUX")
		)
	)
)
